(kicad_pcb
	(version 20260206)
	(generator "pcbnew")
	(generator_version "10.0")
	(general
		(thickness 1.6)
		(legacy_teardrops no)
	)
	(paper "A4")
	(title_block
		(title "netronome-mezz — pcbd0082-001_rev01_jul9_a.brd")
		(comment 1 "Open CloudServer (Microsoft) / footprints 506-514 of 714")
	)
	(layers
		(0 "F.Cu" signal "TOP")
		(4 "In1.Cu" signal "02_GND")
		(6 "In2.Cu" signal "03_SIG")
		(8 "In3.Cu" signal "04_SIG")
		(10 "In4.Cu" signal "05_GND")
		(12 "In5.Cu" signal "06_PWR1")
		(14 "In6.Cu" signal "07_SIG")
		(16 "In7.Cu" signal "08_SIG")
		(18 "In8.Cu" signal "09_GND")
		(2 "B.Cu" signal "BOTTOM")
		(9 "F.Adhes" user "F.Adhesive")
		(11 "B.Adhes" user "B.Adhesive")
		(13 "F.Paste" user "Package Geometry/Pastemask Top")
		(15 "B.Paste" user "Package Geometry/Pastemask Bottom")
		(5 "F.SilkS" user "Ref Des/Silkscreen Top")
		(7 "B.SilkS" user "Ref Des/Silkscreen Bottom")
		(1 "F.Mask" user "Board Geometry/Soldermask Top")
		(3 "B.Mask" user "Board Geometry/Soldermask Bottom")
		(17 "Dwgs.User" user "User.Drawings")
		(19 "Cmts.User" user "User.Comments")
		(21 "Eco1.User" user "User.Eco1")
		(23 "Eco2.User" user "User.Eco2")
		(25 "Edge.Cuts" user "Board Geometry/Outline")
		(27 "Margin" user)
		(31 "F.CrtYd" user "Package Geometry/Place Bound Top")
		(29 "B.CrtYd" user "Package Geometry/Place Bound Bottom")
		(35 "F.Fab" user "Ref Des/Assembly Top")
		(33 "B.Fab" user "Ref Des/Assembly Bottom")
		(45 "User.4" user "COMPVAL_TYPE_BOTTOM")
	)
	(footprint ""
		(layer "B.Cu")
		(at 22.225 8.128)
		(property "Reference" "R25"
			(at 0 0 0)
			(layer "B.SilkS")
			(hide yes)
			(effects
				(font
					(size 1.27 1.27)
				)
				(justify mirror)
			)
		)
		(property "Value" "4.75K"
			(at 0.148158 1.3462 270)
			(unlocked yes)
			(layer "B.Fab")
			(hide yes)
			(effects
				(font
					(size 1.27 0.9652)
					(thickness 0.000001)
				)
				(justify left mirror)
			)
		)
		(property "Device Type" "REST4024"
			(at 0.148158 1.3462 270)
			(unlocked yes)
			(layer "B.Fab")
			(hide yes)
			(effects
				(font
					(size 1.27 0.9652)
					(thickness 0.000001)
				)
				(justify left mirror)
			)
		)
		(duplicate_pad_numbers_are_jumpers no)
		(fp_poly
			(pts
				(xy -0.635 1.0668) (xy -0.635 -1.0668) (xy 0.635 -1.0668) (xy 0.635 1.0668)
			)
			(stroke
				(width 0)
				(type default)
			)
			(fill no)
			(layer "B.CrtYd")
		)
		(fp_line
			(start -0.254 -0.508)
			(end -0.254 0.508)
			(stroke
				(width 0.0254)
				(type default)
			)
			(layer "B.Fab")
		)
		(fp_line
			(start -0.254 0.508)
			(end 0.254 0.508)
			(stroke
				(width 0.0254)
				(type default)
			)
			(layer "B.Fab")
		)
		(fp_line
			(start 0.254 -0.508)
			(end -0.254 -0.508)
			(stroke
				(width 0.0254)
				(type default)
			)
			(layer "B.Fab")
		)
		(fp_line
			(start 0.254 0.508)
			(end 0.254 -0.508)
			(stroke
				(width 0.0254)
				(type default)
			)
			(layer "B.Fab")
		)
		(pad "1" smd rect
			(at 0 -0.4191 180)
			(size 0.508 0.5334)
			(layers "B.Cu" "B.Mask" "B.Paste")
			(net "VDD_3.3V")
		)
		(pad "2" smd rect
			(at 0 0.4191 180)
			(size 0.508 0.5334)
			(layers "B.Cu" "B.Mask" "B.Paste")
			(net "NFP_CFG_SPI_FLASH_HOLD_L")
		)
		(zone
			(layer "B.Cu")
			(hatch none 0.5)
			(connect_pads
				(clearance 0)
			)
			(min_thickness 0.25)
			(keepout
				(tracks not_allowed)
				(vias allowed)
				(pads allowed)
				(copperpour not_allowed)
				(footprints allowed)
			)
			(placement
				(enabled no)
				(sheetname "")
			)
			(fill
				(thermal_gap 0.5)
				(thermal_bridge_width 0.5)
				(island_removal_mode 0)
			)
			(polygon
				(pts
					(xy 22.1996 8.1026) (xy 22.1996 8.1534) (xy 22.2504 8.1534) (xy 22.2504 8.1026)
				)
			)
		)
	)
	(footprint ""
		(layer "B.Cu")
		(at 37.5285 29.845)
		(property "Reference" "C57"
			(at -1.48717 -1.016 270)
			(unlocked yes)
			(layer "B.SilkS")
			(effects
				(font
					(size 0.7874 0.5842)
					(thickness 0.127)
				)
				(justify left mirror)
			)
		)
		(property "Value" "100UF"
			(at 0.78232 0.4826 270)
			(unlocked yes)
			(layer "B.Fab")
			(hide yes)
			(effects
				(font
					(size 1.27 0.9652)
					(thickness 0.000001)
				)
				(justify left mirror)
			)
		)
		(property "Device Type" "CAPC0087"
			(at 0.78232 0.4826 270)
			(unlocked yes)
			(layer "B.Fab")
			(hide yes)
			(effects
				(font
					(size 1.27 0.9652)
					(thickness 0.000001)
				)
				(justify left mirror)
			)
		)
		(duplicate_pad_numbers_are_jumpers no)
		(fp_circle
			(center 0 0)
			(end 0.508 0)
			(stroke
				(width 0.2032)
				(type default)
			)
			(fill no)
			(layer "B.SilkS")
		)
		(fp_poly
			(pts
				(xy 1.27 2.9464) (xy -1.27 2.9464) (xy -1.27 -2.9464) (xy 1.27 -2.9464)
			)
			(stroke
				(width 0)
				(type default)
			)
			(fill no)
			(layer "B.CrtYd")
		)
		(fp_line
			(start -1.016 -2.794)
			(end -1.016 2.794)
			(stroke
				(width 0.0254)
				(type default)
			)
			(layer "B.Fab")
		)
		(fp_line
			(start -1.016 2.794)
			(end 1.016 2.794)
			(stroke
				(width 0.0254)
				(type default)
			)
			(layer "B.Fab")
		)
		(fp_line
			(start 1.016 -2.794)
			(end -1.016 -2.794)
			(stroke
				(width 0.0254)
				(type default)
			)
			(layer "B.Fab")
		)
		(fp_line
			(start 1.016 2.794)
			(end 1.016 -2.794)
			(stroke
				(width 0.0254)
				(type default)
			)
			(layer "B.Fab")
		)
		(pad "1" smd rect
			(at 0 -1.6764 180)
			(size 1.524 1.524)
			(layers "B.Cu" "B.Mask" "B.Paste")
			(net "VDDA_PLL")
		)
		(pad "2" smd rect
			(at 0 1.6764 180)
			(size 1.524 1.524)
			(layers "B.Cu" "B.Mask" "B.Paste")
			(net "GND")
		)
		(zone
			(layer "B.Cu")
			(hatch none 0.5)
			(connect_pads
				(clearance 0)
			)
			(min_thickness 0.25)
			(keepout
				(tracks not_allowed)
				(vias allowed)
				(pads allowed)
				(copperpour not_allowed)
				(footprints allowed)
			)
			(placement
				(enabled no)
				(sheetname "")
			)
			(fill
				(thermal_gap 0.5)
				(thermal_bridge_width 0.5)
				(island_removal_mode 0)
			)
			(polygon
				(pts
					(xy 38.3159 28.956) (xy 36.7411 28.956) (xy 36.7411 29.1084) (xy 38.3159 29.1084)
				)
			)
		)
		(zone
			(layer "B.Cu")
			(hatch none 0.5)
			(connect_pads
				(clearance 0)
			)
			(min_thickness 0.25)
			(keepout
				(tracks not_allowed)
				(vias allowed)
				(pads allowed)
				(copperpour not_allowed)
				(footprints allowed)
			)
			(placement
				(enabled no)
				(sheetname "")
			)
			(fill
				(thermal_gap 0.5)
				(thermal_bridge_width 0.5)
				(island_removal_mode 0)
			)
			(polygon
				(pts
					(xy 38.3159 30.5816) (xy 36.7411 30.5816) (xy 36.7411 30.734) (xy 38.3159 30.734)
				)
			)
		)
		(zone
			(layer "B.Cu")
			(hatch none 0.5)
			(connect_pads
				(clearance 0)
			)
			(min_thickness 0.25)
			(keepout
				(tracks allowed)
				(vias not_allowed)
				(pads allowed)
				(copperpour not_allowed)
				(footprints allowed)
			)
			(placement
				(enabled no)
				(sheetname "")
			)
			(fill
				(thermal_gap 0.5)
				(thermal_bridge_width 0.5)
				(island_removal_mode 0)
			)
			(polygon
				(pts
					(xy 38.3159 31.4452) (xy 36.7411 31.4452) (xy 36.7411 28.956) (xy 38.3159 28.956)
				)
			)
		)
	)
	(footprint ""
		(layer "B.Cu")
		(at 73.851008 18.255996)
		(property "Reference" "V_A-DQ27"
			(at 0 0 0)
			(layer "B.SilkS")
			(hide yes)
			(effects
				(font
					(size 1.27 1.27)
				)
				(justify mirror)
			)
		)
		(property "Value" ""
			(at 0 0 0)
			(layer "B.Fab")
			(effects
				(font
					(size 1.27 1.27)
				)
				(justify mirror)
			)
		)
		(duplicate_pad_numbers_are_jumpers no)
		(pad "1" thru_hole circle
			(at 0 0 180)
			(size 0.4572 0.4572)
			(drill 0.20574)
			(layers "*.Cu" "*.Mask")
			(remove_unused_layers no)
			(net "DDR0_32A_DQ27")
			(clearance 0.1143)
			(thermal_gap 0.1143)
		)
	)
	(footprint ""
		(layer "B.Cu")
		(at 37.6428 21.082 -90)
		(property "Reference" "R205"
			(at 0 0 90)
			(layer "B.SilkS")
			(hide yes)
			(effects
				(font
					(size 1.27 1.27)
				)
				(justify mirror)
			)
		)
		(property "Value" "39.0"
			(at 0.148158 1.3462 180)
			(unlocked yes)
			(layer "B.Fab")
			(hide yes)
			(effects
				(font
					(size 1.27 0.9652)
					(thickness 0.000001)
				)
				(justify left mirror)
			)
		)
		(property "Device Type" "REST0108"
			(at 0.148158 1.3462 180)
			(unlocked yes)
			(layer "B.Fab")
			(hide yes)
			(effects
				(font
					(size 1.27 0.9652)
					(thickness 0.000001)
				)
				(justify left mirror)
			)
		)
		(duplicate_pad_numbers_are_jumpers no)
		(fp_poly
			(pts
				(xy -0.635 1.0668) (xy -0.635 -1.0668) (xy 0.635 -1.0668) (xy 0.635 1.0668)
			)
			(stroke
				(width 0)
				(type default)
			)
			(fill no)
			(layer "B.CrtYd")
		)
		(fp_line
			(start -0.254 0.508)
			(end 0.254 0.508)
			(stroke
				(width 0.0254)
				(type default)
			)
			(layer "B.Fab")
		)
		(fp_line
			(start 0.254 0.508)
			(end 0.254 -0.508)
			(stroke
				(width 0.0254)
				(type default)
			)
			(layer "B.Fab")
		)
		(fp_line
			(start -0.254 -0.508)
			(end -0.254 0.508)
			(stroke
				(width 0.0254)
				(type default)
			)
			(layer "B.Fab")
		)
		(fp_line
			(start 0.254 -0.508)
			(end -0.254 -0.508)
			(stroke
				(width 0.0254)
				(type default)
			)
			(layer "B.Fab")
		)
		(pad "1" smd rect
			(at 0 -0.4191 90)
			(size 0.508 0.5334)
			(layers "B.Cu" "B.Mask" "B.Paste")
			(net "_NFP_CFG_SPI_FLASH_SCK")
		)
		(pad "2" smd rect
			(at 0 0.4191 90)
			(size 0.508 0.5334)
			(layers "B.Cu" "B.Mask" "B.Paste")
			(net "NFP_CFG_SPI_FLASH_SCK")
		)
		(zone
			(layer "B.Cu")
			(hatch none 0.5)
			(connect_pads
				(clearance 0)
			)
			(min_thickness 0.25)
			(keepout
				(tracks not_allowed)
				(vias allowed)
				(pads allowed)
				(copperpour not_allowed)
				(footprints allowed)
			)
			(placement
				(enabled no)
				(sheetname "")
			)
			(fill
				(thermal_gap 0.5)
				(thermal_bridge_width 0.5)
				(island_removal_mode 0)
			)
			(polygon
				(pts
					(xy 37.6682 21.0566) (xy 37.6174 21.0566) (xy 37.6174 21.1074) (xy 37.6682 21.1074)
				)
			)
		)
	)
	(footprint ""
		(layer "B.Cu")
		(at 44.73702 20.041997 -90)
		(property "Reference" "R320"
			(at 0 0 90)
			(layer "B.SilkS")
			(hide yes)
			(effects
				(font
					(size 1.27 1.27)
				)
				(justify mirror)
			)
		)
		(property "Value" ""
			(at 0 0 90)
			(layer "B.Fab")
			(effects
				(font
					(size 1.27 1.27)
				)
				(justify mirror)
			)
		)
		(duplicate_pad_numbers_are_jumpers no)
		(fp_circle
			(center 0 0)
			(end 0 -0.104648)
			(stroke
				(width 0.1016)
				(type default)
			)
			(fill no)
			(layer "B.SilkS")
		)
		(fp_poly
			(pts
				(xy 0.381 -0.889) (xy 0.381 0.889) (xy -0.381 0.889) (xy -0.381 -0.889)
			)
			(stroke
				(width 0)
				(type default)
			)
			(fill no)
			(layer "B.CrtYd")
		)
		(fp_line
			(start -0.508 1.016)
			(end 0.508 1.016)
			(stroke
				(width 0.0254)
				(type default)
			)
			(layer "B.Fab")
		)
		(fp_line
			(start 0.508 1.016)
			(end 0.508 -1.016)
			(stroke
				(width 0.0254)
				(type default)
			)
			(layer "B.Fab")
		)
		(fp_line
			(start -0.508 -1.016)
			(end -0.508 1.016)
			(stroke
				(width 0.0254)
				(type default)
			)
			(layer "B.Fab")
		)
		(fp_line
			(start 0.254 -1.016)
			(end -0.508 -1.016)
			(stroke
				(width 0.0254)
				(type default)
			)
			(layer "B.Fab")
		)
		(fp_line
			(start 0.508 -1.016)
			(end 0.254 -1.016)
			(stroke
				(width 0.0254)
				(type default)
			)
			(layer "B.Fab")
		)
		(pad "1" smd custom
			(at 0 -0.500126 90)
			(size 0.127 0.127)
			(layers "B.Cu" "B.Mask" "B.Paste")
			(net "GND")
			(options
				(clearance outline)
				(anchor circle)
			)
			(primitives
				(gr_poly
					(pts
						(xy -0.1778 0.254) (xy 0.1778 0.254) (xy 0.254 0.1778) (xy 0.254 -0.1778) (xy 0.1778 -0.254) (xy -0.1778 -0.254)
						(xy -0.254 -0.1778) (xy -0.254 0.1778)
					)
					(width 0)
					(fill yes)
				)
			)
		)
		(pad "2" smd custom
			(at 0 0.500126 90)
			(size 0.127 0.127)
			(layers "B.Cu" "B.Mask" "B.Paste")
			(net "NFP_CLK_REF_P")
			(options
				(clearance outline)
				(anchor circle)
			)
			(primitives
				(gr_poly
					(pts
						(xy -0.1778 0.254) (xy 0.1778 0.254) (xy 0.254 0.1778) (xy 0.254 -0.1778) (xy 0.1778 -0.254) (xy -0.1778 -0.254)
						(xy -0.254 -0.1778) (xy -0.254 0.1778)
					)
					(width 0)
					(fill yes)
				)
			)
		)
	)
	(footprint ""
		(layer "B.Cu")
		(at 82.65099 7.498994)
		(property "Reference" "V1_A-A04"
			(at 0 0 0)
			(layer "B.SilkS")
			(hide yes)
			(effects
				(font
					(size 1.27 1.27)
				)
				(justify mirror)
			)
		)
		(property "Value" ""
			(at 0 0 0)
			(layer "B.Fab")
			(effects
				(font
					(size 1.27 1.27)
				)
				(justify mirror)
			)
		)
		(duplicate_pad_numbers_are_jumpers no)
		(pad "1" thru_hole circle
			(at 0 0 180)
			(size 0.4572 0.4572)
			(drill 0.20574)
			(layers "*.Cu" "*.Mask")
			(remove_unused_layers no)
			(net "DDR0_32A_A4")
			(clearance 0.1143)
			(thermal_gap 0.1143)
		)
	)
	(footprint ""
		(layer "B.Cu")
		(at 37.084 46.736)
		(property "Reference" "TP8"
			(at 0 0 0)
			(layer "B.SilkS")
			(hide yes)
			(effects
				(font
					(size 1.27 1.27)
				)
				(justify mirror)
			)
		)
		(property "Value" "*"
			(at 0.4826 -0.14732 0)
			(unlocked yes)
			(layer "B.Fab")
			(hide yes)
			(effects
				(font
					(size 1.27 0.9652)
					(thickness 0.000001)
				)
				(justify left mirror)
			)
		)
		(property "Device Type" "TP_SMALL"
			(at 0.4826 -0.14732 0)
			(unlocked yes)
			(layer "B.Fab")
			(hide yes)
			(effects
				(font
					(size 1.27 0.9652)
					(thickness 0.000001)
				)
				(justify left mirror)
			)
		)
		(duplicate_pad_numbers_are_jumpers no)
		(fp_line
			(start -0.8636 -0.8636)
			(end 0.8636 -0.8636)
			(stroke
				(width 0.1524)
				(type default)
			)
			(layer "B.SilkS")
		)
		(fp_line
			(start -0.8636 0.8636)
			(end -0.8636 -0.8636)
			(stroke
				(width 0.1524)
				(type default)
			)
			(layer "B.SilkS")
		)
		(fp_line
			(start 0.8636 -0.8636)
			(end 0.8636 0.8636)
			(stroke
				(width 0.1524)
				(type default)
			)
			(layer "B.SilkS")
		)
		(fp_line
			(start 0.8636 0.8636)
			(end -0.8636 0.8636)
			(stroke
				(width 0.1524)
				(type default)
			)
			(layer "B.SilkS")
		)
		(fp_poly
			(pts
				(xy 0.635 -0.635) (xy 0.635 0.635) (xy -0.635 0.635) (xy -0.635 -0.635)
			)
			(stroke
				(width 0)
				(type default)
			)
			(fill no)
			(layer "B.CrtYd")
		)
		(pad "1" smd rect
			(at 0 0 180)
			(size 1.27 1.27)
			(layers "B.Cu" "B.Mask" "B.Paste")
			(net "NFP_JTAG_ARM_TDO")
		)
	)
	(footprint ""
		(layer "B.Cu")
		(at 40.894 46.736)
		(property "Reference" "TP5"
			(at 3.302 1.16967 0)
			(unlocked yes)
			(layer "B.SilkS")
			(effects
				(font
					(size 0.7874 0.5842)
					(thickness 0.127)
				)
				(justify left mirror)
			)
		)
		(property "Value" "*"
			(at 0.4826 -0.14732 0)
			(unlocked yes)
			(layer "B.Fab")
			(hide yes)
			(effects
				(font
					(size 1.27 0.9652)
					(thickness 0.000001)
				)
				(justify left mirror)
			)
		)
		(property "Device Type" "TP_SMALL"
			(at 0.4826 -0.14732 0)
			(unlocked yes)
			(layer "B.Fab")
			(hide yes)
			(effects
				(font
					(size 1.27 0.9652)
					(thickness 0.000001)
				)
				(justify left mirror)
			)
		)
		(duplicate_pad_numbers_are_jumpers no)
		(fp_line
			(start -0.8636 -0.8636)
			(end 0.8636 -0.8636)
			(stroke
				(width 0.1524)
				(type default)
			)
			(layer "B.SilkS")
		)
		(fp_line
			(start -0.8636 0.8636)
			(end -0.8636 -0.8636)
			(stroke
				(width 0.1524)
				(type default)
			)
			(layer "B.SilkS")
		)
		(fp_line
			(start 0.8636 -0.8636)
			(end 0.8636 0.8636)
			(stroke
				(width 0.1524)
				(type default)
			)
			(layer "B.SilkS")
		)
		(fp_line
			(start 0.8636 0.8636)
			(end -0.8636 0.8636)
			(stroke
				(width 0.1524)
				(type default)
			)
			(layer "B.SilkS")
		)
		(fp_poly
			(pts
				(xy 0.635 -0.635) (xy 0.635 0.635) (xy -0.635 0.635) (xy -0.635 -0.635)
			)
			(stroke
				(width 0)
				(type default)
			)
			(fill no)
			(layer "B.CrtYd")
		)
		(pad "1" smd rect
			(at 0 0 180)
			(size 1.27 1.27)
			(layers "B.Cu" "B.Mask" "B.Paste")
			(net "NFP_JTAG_ARM_TRST_L")
		)
	)
	(footprint ""
		(layer "B.Cu")
		(at 34.163 26.162 90)
		(property "Reference" "R48"
			(at 0 0 90)
			(layer "B.SilkS")
			(hide yes)
			(effects
				(font
					(size 1.27 1.27)
				)
				(justify mirror)
			)
		)
		(property "Value" "4.75K"
			(at 0.148158 1.3462 0)
			(unlocked yes)
			(layer "B.Fab")
			(hide yes)
			(effects
				(font
					(size 1.27 0.9652)
					(thickness 0.000001)
				)
				(justify left mirror)
			)
		)
		(property "Device Type" "REST4024"
			(at 0.148158 1.3462 0)
			(unlocked yes)
			(layer "B.Fab")
			(hide yes)
			(effects
				(font
					(size 1.27 0.9652)
					(thickness 0.000001)
				)
				(justify left mirror)
			)
		)
		(duplicate_pad_numbers_are_jumpers no)
		(fp_poly
			(pts
				(xy -0.635 1.0668) (xy -0.635 -1.0668) (xy 0.635 -1.0668) (xy 0.635 1.0668)
			)
			(stroke
				(width 0)
				(type default)
			)
			(fill no)
			(layer "B.CrtYd")
		)
		(fp_line
			(start 0.254 -0.508)
			(end -0.254 -0.508)
			(stroke
				(width 0.0254)
				(type default)
			)
			(layer "B.Fab")
		)
		(fp_line
			(start -0.254 -0.508)
			(end -0.254 0.508)
			(stroke
				(width 0.0254)
				(type default)
			)
			(layer "B.Fab")
		)
		(fp_line
			(start 0.254 0.508)
			(end 0.254 -0.508)
			(stroke
				(width 0.0254)
				(type default)
			)
			(layer "B.Fab")
		)
		(fp_line
			(start -0.254 0.508)
			(end 0.254 0.508)
			(stroke
				(width 0.0254)
				(type default)
			)
			(layer "B.Fab")
		)
		(pad "1" smd rect
			(at 0 -0.4191 270)
			(size 0.508 0.5334)
			(layers "B.Cu" "B.Mask" "B.Paste")
			(net "EXT_3.3V")
		)
		(pad "2" smd rect
			(at 0 0.4191 270)
			(size 0.508 0.5334)
			(layers "B.Cu" "B.Mask" "B.Paste")
			(net "HOST_RESET_REQ_L")
		)
		(zone
			(layer "B.Cu")
			(hatch none 0.5)
			(connect_pads
				(clearance 0)
			)
			(min_thickness 0.25)
			(keepout
				(tracks not_allowed)
				(vias allowed)
				(pads allowed)
				(copperpour not_allowed)
				(footprints allowed)
			)
			(placement
				(enabled no)
				(sheetname "")
			)
			(fill
				(thermal_gap 0.5)
				(thermal_bridge_width 0.5)
				(island_removal_mode 0)
			)
			(polygon
				(pts
					(xy 34.1376 26.1874) (xy 34.1884 26.1874) (xy 34.1884 26.1366) (xy 34.1376 26.1366)
				)
			)
		)
	)
)
